(kicad_pcb
	(version 20260206)
	(generator "pcbnew")
	(generator_version "10.0")
	(general
		(thickness 1.6)
		(legacy_teardrops no)
	)
	(paper "A4")
	(title_block
		(title "01162023_DA0F0TEBIF0_F0T_Expander_BD_F_brd_V02_OCP.brd")
		(comment 1 "Grand Teton / footprints 7557-7564 of 9728")
	)
	(layers
		(0 "F.Cu" signal "TOP")
		(4 "In1.Cu" signal "GND")
		(6 "In2.Cu" signal "VCC")
		(8 "In3.Cu" signal "VCC1")
		(10 "In4.Cu" signal "GND1")
		(12 "In5.Cu" signal "IN1")
		(14 "In6.Cu" signal "GND2")
		(16 "In7.Cu" signal "IN2")
		(18 "In8.Cu" signal "GND3")
		(20 "In9.Cu" signal "IN3")
		(22 "In10.Cu" signal "GND4")
		(24 "In11.Cu" signal "IN4")
		(26 "In12.Cu" signal "GND5")
		(28 "In13.Cu" signal "IN5")
		(30 "In14.Cu" signal "GND6")
		(32 "In15.Cu" signal "IN6")
		(34 "In16.Cu" signal "GND7")
		(2 "B.Cu" signal "BOTTOM")
		(9 "F.Adhes" user "F.Adhesive")
		(11 "B.Adhes" user "B.Adhesive")
		(13 "F.Paste" user "Package Geometry/Pastemask Top")
		(15 "B.Paste" user "Package Geometry/Pastemask Bottom")
		(5 "F.SilkS" user "Ref Des/Silkscreen Top")
		(7 "B.SilkS" user "Ref Des/Silkscreen Bottom")
		(1 "F.Mask" user "Board Geometry/Soldermask Top")
		(3 "B.Mask" user "Board Geometry/Soldermask Bottom")
		(17 "Dwgs.User" user "User.Drawings")
		(19 "Cmts.User" user "User.Comments")
		(21 "Eco1.User" user "User.Eco1")
		(23 "Eco2.User" user "User.Eco2")
		(25 "Edge.Cuts" user "Board Geometry/Outline")
		(27 "Margin" user)
		(31 "F.CrtYd" user "Package Geometry/Place Bound Top")
		(29 "B.CrtYd" user "Package Geometry/Place Bound Bottom")
		(35 "F.Fab" user "Ref Des/Assembly Top")
		(33 "B.Fab" user "Ref Des/Assembly Bottom")
	)
	(footprint ""
		(layer "B.Cu")
		(at 193.641726 -102.088696 180)
		(property "Reference" "R170"
			(at 0 0 0)
			(layer "B.SilkS")
			(hide yes)
			(effects
				(font
					(size 1.27 1.27)
				)
				(justify mirror)
			)
		)
		(property "Value" ""
			(at 0 0 0)
			(layer "B.Fab")
			(effects
				(font
					(size 1.27 1.27)
				)
				(justify mirror)
			)
		)
		(duplicate_pad_numbers_are_jumpers no)
		(fp_line
			(start 0.7874 0.4064)
			(end 0.7874 -0.4064)
			(stroke
				(width 0.1524)
				(type default)
			)
			(layer "B.SilkS")
		)
		(fp_line
			(start 0.7874 -0.4064)
			(end -0.7874 -0.4064)
			(stroke
				(width 0.1524)
				(type default)
			)
			(layer "B.SilkS")
		)
		(fp_line
			(start -0.7874 0.4064)
			(end 0.7874 0.4064)
			(stroke
				(width 0.1524)
				(type default)
			)
			(layer "B.SilkS")
		)
		(fp_line
			(start -0.7874 -0.4064)
			(end -0.7874 0.4064)
			(stroke
				(width 0.1524)
				(type default)
			)
			(layer "B.SilkS")
		)
		(fp_line
			(start 0.67945 0.3048)
			(end 0.67945 -0.305054)
			(stroke
				(width 0.1)
				(type default)
			)
			(layer "B.Fab")
		)
		(fp_line
			(start 0.67945 -0.305054)
			(end 0.12065 -0.305054)
			(stroke
				(width 0.1)
				(type default)
			)
			(layer "B.Fab")
		)
		(fp_line
			(start 0.12065 0.3048)
			(end 0.67945 0.3048)
			(stroke
				(width 0.1)
				(type default)
			)
			(layer "B.Fab")
		)
		(fp_line
			(start 0.12065 0.2794)
			(end 0.12065 0.3048)
			(stroke
				(width 0.1)
				(type default)
			)
			(layer "B.Fab")
		)
		(fp_line
			(start 0.12065 -0.2794)
			(end -0.12065 -0.2794)
			(stroke
				(width 0.1)
				(type default)
			)
			(layer "B.Fab")
		)
		(fp_line
			(start 0.12065 -0.305054)
			(end 0.12065 -0.2794)
			(stroke
				(width 0.1)
				(type default)
			)
			(layer "B.Fab")
		)
		(fp_line
			(start -0.120396 0.3048)
			(end -0.120396 0.2794)
			(stroke
				(width 0.1)
				(type default)
			)
			(layer "B.Fab")
		)
		(fp_line
			(start -0.120396 0.2794)
			(end 0.12065 0.2794)
			(stroke
				(width 0.1)
				(type default)
			)
			(layer "B.Fab")
		)
		(fp_line
			(start -0.12065 -0.2794)
			(end -0.12065 -0.3048)
			(stroke
				(width 0.1)
				(type default)
			)
			(layer "B.Fab")
		)
		(fp_line
			(start -0.12065 -0.3048)
			(end -0.67945 -0.3048)
			(stroke
				(width 0.1)
				(type default)
			)
			(layer "B.Fab")
		)
		(fp_line
			(start -0.67945 0.3048)
			(end -0.120396 0.3048)
			(stroke
				(width 0.1)
				(type default)
			)
			(layer "B.Fab")
		)
		(fp_line
			(start -0.67945 -0.3048)
			(end -0.67945 0.3048)
			(stroke
				(width 0.1)
				(type default)
			)
			(layer "B.Fab")
		)
		(pad "1" smd circle
			(at 0.40005 0)
			(size 0 0)
			(layers "B.Cu" "B.Mask" "B.Paste")
			(net "NCSI_NIC3_RXD1")
		)
		(pad "2" smd circle
			(at -0.40005 0)
			(size 0 0)
			(layers "B.Cu" "B.Mask" "B.Paste")
			(net "GND")
		)
	)
	(footprint ""
		(layer "B.Cu")
		(at 62.024768 -297.79976 90)
		(property "Reference" "C1115"
			(at 0 0 90)
			(layer "B.SilkS")
			(hide yes)
			(effects
				(font
					(size 1.27 1.27)
				)
				(justify mirror)
			)
		)
		(property "Value" ""
			(at 0 0 90)
			(layer "B.Fab")
			(effects
				(font
					(size 1.27 1.27)
				)
				(justify mirror)
			)
		)
		(duplicate_pad_numbers_are_jumpers no)
		(fp_line
			(start 0.299974 -0.150114)
			(end -0.299974 -0.150114)
			(stroke
				(width 0.1)
				(type default)
			)
			(layer "B.Fab")
		)
		(fp_line
			(start -0.299974 -0.150114)
			(end -0.299974 0.150114)
			(stroke
				(width 0.1)
				(type default)
			)
			(layer "B.Fab")
		)
		(fp_line
			(start 0.299974 0.150114)
			(end 0.299974 -0.150114)
			(stroke
				(width 0.1)
				(type default)
			)
			(layer "B.Fab")
		)
		(fp_line
			(start -0.299974 0.150114)
			(end 0.299974 0.150114)
			(stroke
				(width 0.1)
				(type default)
			)
			(layer "B.Fab")
		)
		(pad "1" smd rect
			(at 0.2667 0 270)
			(size 0.3048 0.381)
			(layers "B.Cu" "B.Mask" "B.Paste")
			(net "P0V8_PEX0")
		)
		(pad "2" smd rect
			(at -0.2667 0 270)
			(size 0.3048 0.381)
			(layers "B.Cu" "B.Mask" "B.Paste")
			(net "GND")
		)
	)
	(footprint ""
		(layer "B.Cu")
		(at 425.124118 -114.35207 90)
		(property "Reference" "C958"
			(at 0 0 90)
			(layer "B.SilkS")
			(hide yes)
			(effects
				(font
					(size 1.27 1.27)
				)
				(justify mirror)
			)
		)
		(property "Value" ""
			(at 0 0 90)
			(layer "B.Fab")
			(effects
				(font
					(size 1.27 1.27)
				)
				(justify mirror)
			)
		)
		(duplicate_pad_numbers_are_jumpers no)
		(fp_line
			(start 0.7874 -0.4064)
			(end -0.7874 -0.4064)
			(stroke
				(width 0.1524)
				(type default)
			)
			(layer "B.SilkS")
		)
		(fp_line
			(start -0.7874 -0.4064)
			(end -0.7874 0.4064)
			(stroke
				(width 0.1524)
				(type default)
			)
			(layer "B.SilkS")
		)
		(fp_line
			(start 0.7874 0.4064)
			(end 0.7874 -0.4064)
			(stroke
				(width 0.1524)
				(type default)
			)
			(layer "B.SilkS")
		)
		(fp_line
			(start -0.7874 0.4064)
			(end 0.7874 0.4064)
			(stroke
				(width 0.1524)
				(type default)
			)
			(layer "B.SilkS")
		)
		(fp_line
			(start 0.67945 -0.305054)
			(end 0.12065 -0.305054)
			(stroke
				(width 0.1)
				(type default)
			)
			(layer "B.Fab")
		)
		(fp_line
			(start 0.12065 -0.305054)
			(end 0.12065 -0.2794)
			(stroke
				(width 0.1)
				(type default)
			)
			(layer "B.Fab")
		)
		(fp_line
			(start -0.12065 -0.3048)
			(end -0.67945 -0.3048)
			(stroke
				(width 0.1)
				(type default)
			)
			(layer "B.Fab")
		)
		(fp_line
			(start -0.67945 -0.3048)
			(end -0.67945 0.3048)
			(stroke
				(width 0.1)
				(type default)
			)
			(layer "B.Fab")
		)
		(fp_line
			(start 0.12065 -0.2794)
			(end -0.12065 -0.2794)
			(stroke
				(width 0.1)
				(type default)
			)
			(layer "B.Fab")
		)
		(fp_line
			(start -0.12065 -0.2794)
			(end -0.12065 -0.3048)
			(stroke
				(width 0.1)
				(type default)
			)
			(layer "B.Fab")
		)
		(fp_line
			(start 0.12065 0.2794)
			(end 0.12065 0.3048)
			(stroke
				(width 0.1)
				(type default)
			)
			(layer "B.Fab")
		)
		(fp_line
			(start -0.120396 0.2794)
			(end 0.12065 0.2794)
			(stroke
				(width 0.1)
				(type default)
			)
			(layer "B.Fab")
		)
		(fp_line
			(start 0.67945 0.3048)
			(end 0.67945 -0.305054)
			(stroke
				(width 0.1)
				(type default)
			)
			(layer "B.Fab")
		)
		(fp_line
			(start 0.12065 0.3048)
			(end 0.67945 0.3048)
			(stroke
				(width 0.1)
				(type default)
			)
			(layer "B.Fab")
		)
		(fp_line
			(start -0.120396 0.3048)
			(end -0.120396 0.2794)
			(stroke
				(width 0.1)
				(type default)
			)
			(layer "B.Fab")
		)
		(fp_line
			(start -0.67945 0.3048)
			(end -0.120396 0.3048)
			(stroke
				(width 0.1)
				(type default)
			)
			(layer "B.Fab")
		)
		(pad "1" smd circle
			(at 0.40005 0 270)
			(size 0 0)
			(layers "B.Cu" "B.Mask" "B.Paste")
			(net "P3V3_NIC7")
		)
		(pad "2" smd circle
			(at -0.40005 0 270)
			(size 0 0)
			(layers "B.Cu" "B.Mask" "B.Paste")
			(net "GND")
		)
	)
	(footprint ""
		(layer "B.Cu")
		(at 288.99993 -299.699934 -90)
		(property "Reference" "C1709"
			(at 0 0 90)
			(layer "B.SilkS")
			(hide yes)
			(effects
				(font
					(size 1.27 1.27)
				)
				(justify mirror)
			)
		)
		(property "Value" ""
			(at 0 0 90)
			(layer "B.Fab")
			(effects
				(font
					(size 1.27 1.27)
				)
				(justify mirror)
			)
		)
		(duplicate_pad_numbers_are_jumpers no)
		(fp_line
			(start -0.299974 0.150114)
			(end 0.299974 0.150114)
			(stroke
				(width 0.1)
				(type default)
			)
			(layer "B.Fab")
		)
		(fp_line
			(start 0.299974 0.150114)
			(end 0.299974 -0.150114)
			(stroke
				(width 0.1)
				(type default)
			)
			(layer "B.Fab")
		)
		(fp_line
			(start -0.299974 -0.150114)
			(end -0.299974 0.150114)
			(stroke
				(width 0.1)
				(type default)
			)
			(layer "B.Fab")
		)
		(fp_line
			(start 0.299974 -0.150114)
			(end -0.299974 -0.150114)
			(stroke
				(width 0.1)
				(type default)
			)
			(layer "B.Fab")
		)
		(pad "1" smd rect
			(at 0.2667 0 90)
			(size 0.3048 0.381)
			(layers "B.Cu" "B.Mask" "B.Paste")
			(net "P0V8_SERDES_VDDA_PEX2")
		)
		(pad "2" smd rect
			(at -0.2667 0 90)
			(size 0.3048 0.381)
			(layers "B.Cu" "B.Mask" "B.Paste")
			(net "GND")
		)
	)
	(footprint ""
		(layer "B.Cu")
		(at 67.724782 -286.399732 90)
		(property "Reference" "C2953"
			(at 0 0 90)
			(layer "B.SilkS")
			(hide yes)
			(effects
				(font
					(size 1.27 1.27)
				)
				(justify mirror)
			)
		)
		(property "Value" ""
			(at 0 0 90)
			(layer "B.Fab")
			(effects
				(font
					(size 1.27 1.27)
				)
				(justify mirror)
			)
		)
		(duplicate_pad_numbers_are_jumpers no)
		(fp_line
			(start 0.299974 -0.150114)
			(end -0.299974 -0.150114)
			(stroke
				(width 0.1)
				(type default)
			)
			(layer "B.Fab")
		)
		(fp_line
			(start -0.299974 -0.150114)
			(end -0.299974 0.150114)
			(stroke
				(width 0.1)
				(type default)
			)
			(layer "B.Fab")
		)
		(fp_line
			(start 0.299974 0.150114)
			(end 0.299974 -0.150114)
			(stroke
				(width 0.1)
				(type default)
			)
			(layer "B.Fab")
		)
		(fp_line
			(start -0.299974 0.150114)
			(end 0.299974 0.150114)
			(stroke
				(width 0.1)
				(type default)
			)
			(layer "B.Fab")
		)
		(pad "1" smd rect
			(at 0.2667 0 270)
			(size 0.3048 0.381)
			(layers "B.Cu" "B.Mask" "B.Paste")
			(net "P1V25_SERDES_VDDPLL_PEX0")
		)
		(pad "2" smd rect
			(at -0.2667 0 270)
			(size 0.3048 0.381)
			(layers "B.Cu" "B.Mask" "B.Paste")
			(net "GND")
		)
	)
	(footprint ""
		(layer "B.Cu")
		(at 354.500434 -324.941438 -90)
		(property "Reference" "C4381"
			(at 0 0 90)
			(layer "B.SilkS")
			(hide yes)
			(effects
				(font
					(size 1.27 1.27)
				)
				(justify mirror)
			)
		)
		(property "Value" ""
			(at 0 0 90)
			(layer "B.Fab")
			(effects
				(font
					(size 1.27 1.27)
				)
				(justify mirror)
			)
		)
		(duplicate_pad_numbers_are_jumpers no)
		(fp_line
			(start -1.2954 0.5842)
			(end 1.2954 0.5842)
			(stroke
				(width 0.1524)
				(type default)
			)
			(layer "B.SilkS")
		)
		(fp_line
			(start 1.2954 0.5842)
			(end 1.2954 -0.5842)
			(stroke
				(width 0.1524)
				(type default)
			)
			(layer "B.SilkS")
		)
		(fp_line
			(start -1.2954 -0.5842)
			(end -1.2954 0.5842)
			(stroke
				(width 0.1524)
				(type default)
			)
			(layer "B.SilkS")
		)
		(fp_line
			(start 1.2954 -0.5842)
			(end -1.2954 -0.5842)
			(stroke
				(width 0.1524)
				(type default)
			)
			(layer "B.SilkS")
		)
		(fp_line
			(start -0.8636 0.4572)
			(end 0.8636 0.4572)
			(stroke
				(width 0.1)
				(type default)
			)
			(layer "B.Fab")
		)
		(fp_line
			(start 0.8636 0.4572)
			(end 0.8636 0.4064)
			(stroke
				(width 0.1)
				(type default)
			)
			(layer "B.Fab")
		)
		(fp_line
			(start -1.1938 0.4064)
			(end -0.8636 0.4064)
			(stroke
				(width 0.1)
				(type default)
			)
			(layer "B.Fab")
		)
		(fp_line
			(start -0.8636 0.4064)
			(end -0.8636 0.4572)
			(stroke
				(width 0.1)
				(type default)
			)
			(layer "B.Fab")
		)
		(fp_line
			(start 0.8636 0.4064)
			(end 1.1938 0.4064)
			(stroke
				(width 0.1)
				(type default)
			)
			(layer "B.Fab")
		)
		(fp_line
			(start 1.1938 0.4064)
			(end 1.1938 -0.4064)
			(stroke
				(width 0.1)
				(type default)
			)
			(layer "B.Fab")
		)
		(fp_line
			(start -1.1938 -0.4064)
			(end -1.1938 0.4064)
			(stroke
				(width 0.1)
				(type default)
			)
			(layer "B.Fab")
		)
		(fp_line
			(start -0.8636 -0.4064)
			(end -1.1938 -0.4064)
			(stroke
				(width 0.1)
				(type default)
			)
			(layer "B.Fab")
		)
		(fp_line
			(start 0.8636 -0.4064)
			(end 0.8636 -0.4572)
			(stroke
				(width 0.1)
				(type default)
			)
			(layer "B.Fab")
		)
		(fp_line
			(start 1.1938 -0.4064)
			(end 0.8636 -0.4064)
			(stroke
				(width 0.1)
				(type default)
			)
			(layer "B.Fab")
		)
		(fp_line
			(start -0.8636 -0.4572)
			(end -0.8636 -0.4064)
			(stroke
				(width 0.1)
				(type default)
			)
			(layer "B.Fab")
		)
		(fp_line
			(start 0.8636 -0.4572)
			(end -0.8636 -0.4572)
			(stroke
				(width 0.1)
				(type default)
			)
			(layer "B.Fab")
		)
		(pad "1" smd rect
			(at 0.7366 0 180)
			(size 0.7112 0.8128)
			(layers "B.Cu" "B.Mask" "B.Paste")
			(net "P0V8_SERDES_VDDA_PEX3_C7")
		)
		(pad "2" smd rect
			(at -0.7366 0 180)
			(size 0.7112 0.8128)
			(layers "B.Cu" "B.Mask" "B.Paste")
			(net "GND")
		)
	)
	(footprint ""
		(layer "B.Cu")
		(at 113.514124 -330.59243 180)
		(property "Reference" "R1219"
			(at 0 0 0)
			(layer "B.SilkS")
			(hide yes)
			(effects
				(font
					(size 1.27 1.27)
				)
				(justify mirror)
			)
		)
		(property "Value" ""
			(at 0 0 0)
			(layer "B.Fab")
			(effects
				(font
					(size 1.27 1.27)
				)
				(justify mirror)
			)
		)
		(duplicate_pad_numbers_are_jumpers no)
		(fp_line
			(start 0.7874 0.4064)
			(end 0.7874 -0.4064)
			(stroke
				(width 0.1524)
				(type default)
			)
			(layer "B.SilkS")
		)
		(fp_line
			(start 0.7874 -0.4064)
			(end -0.7874 -0.4064)
			(stroke
				(width 0.1524)
				(type default)
			)
			(layer "B.SilkS")
		)
		(fp_line
			(start -0.7874 0.4064)
			(end 0.7874 0.4064)
			(stroke
				(width 0.1524)
				(type default)
			)
			(layer "B.SilkS")
		)
		(fp_line
			(start -0.7874 -0.4064)
			(end -0.7874 0.4064)
			(stroke
				(width 0.1524)
				(type default)
			)
			(layer "B.SilkS")
		)
		(fp_line
			(start 0.67945 0.3048)
			(end 0.67945 -0.305054)
			(stroke
				(width 0.1)
				(type default)
			)
			(layer "B.Fab")
		)
		(fp_line
			(start 0.67945 -0.305054)
			(end 0.12065 -0.305054)
			(stroke
				(width 0.1)
				(type default)
			)
			(layer "B.Fab")
		)
		(fp_line
			(start 0.12065 0.3048)
			(end 0.67945 0.3048)
			(stroke
				(width 0.1)
				(type default)
			)
			(layer "B.Fab")
		)
		(fp_line
			(start 0.12065 0.2794)
			(end 0.12065 0.3048)
			(stroke
				(width 0.1)
				(type default)
			)
			(layer "B.Fab")
		)
		(fp_line
			(start 0.12065 -0.2794)
			(end -0.12065 -0.2794)
			(stroke
				(width 0.1)
				(type default)
			)
			(layer "B.Fab")
		)
		(fp_line
			(start 0.12065 -0.305054)
			(end 0.12065 -0.2794)
			(stroke
				(width 0.1)
				(type default)
			)
			(layer "B.Fab")
		)
		(fp_line
			(start -0.120396 0.3048)
			(end -0.120396 0.2794)
			(stroke
				(width 0.1)
				(type default)
			)
			(layer "B.Fab")
		)
		(fp_line
			(start -0.120396 0.2794)
			(end 0.12065 0.2794)
			(stroke
				(width 0.1)
				(type default)
			)
			(layer "B.Fab")
		)
		(fp_line
			(start -0.12065 -0.2794)
			(end -0.12065 -0.3048)
			(stroke
				(width 0.1)
				(type default)
			)
			(layer "B.Fab")
		)
		(fp_line
			(start -0.12065 -0.3048)
			(end -0.67945 -0.3048)
			(stroke
				(width 0.1)
				(type default)
			)
			(layer "B.Fab")
		)
		(fp_line
			(start -0.67945 0.3048)
			(end -0.120396 0.3048)
			(stroke
				(width 0.1)
				(type default)
			)
			(layer "B.Fab")
		)
		(fp_line
			(start -0.67945 -0.3048)
			(end -0.67945 0.3048)
			(stroke
				(width 0.1)
				(type default)
			)
			(layer "B.Fab")
		)
		(pad "1" smd circle
			(at 0.40005 0)
			(size 0 0)
			(layers "B.Cu" "B.Mask" "B.Paste")
			(net "CLK_100M_MB_0_R_DN")
		)
		(pad "2" smd circle
			(at -0.40005 0)
			(size 0 0)
			(layers "B.Cu" "B.Mask" "B.Paste")
			(net "CLK_100M_MB_0_DN")
		)
	)
	(footprint ""
		(layer "B.Cu")
		(at 204.132942 -259.311648 90)
		(property "Reference" "R6342"
			(at 0 0 90)
			(layer "B.SilkS")
			(hide yes)
			(effects
				(font
					(size 1.27 1.27)
				)
				(justify mirror)
			)
		)
		(property "Value" ""
			(at 0 0 90)
			(layer "B.Fab")
			(effects
				(font
					(size 1.27 1.27)
				)
				(justify mirror)
			)
		)
		(duplicate_pad_numbers_are_jumpers no)
		(fp_line
			(start 0.7874 -0.4064)
			(end -0.7874 -0.4064)
			(stroke
				(width 0.1524)
				(type default)
			)
			(layer "B.SilkS")
		)
		(fp_line
			(start -0.7874 -0.4064)
			(end -0.7874 0.4064)
			(stroke
				(width 0.1524)
				(type default)
			)
			(layer "B.SilkS")
		)
		(fp_line
			(start 0.7874 0.4064)
			(end 0.7874 -0.4064)
			(stroke
				(width 0.1524)
				(type default)
			)
			(layer "B.SilkS")
		)
		(fp_line
			(start -0.7874 0.4064)
			(end 0.7874 0.4064)
			(stroke
				(width 0.1524)
				(type default)
			)
			(layer "B.SilkS")
		)
		(fp_line
			(start 0.67945 -0.305054)
			(end 0.12065 -0.305054)
			(stroke
				(width 0.1)
				(type default)
			)
			(layer "B.Fab")
		)
		(fp_line
			(start 0.12065 -0.305054)
			(end 0.12065 -0.2794)
			(stroke
				(width 0.1)
				(type default)
			)
			(layer "B.Fab")
		)
		(fp_line
			(start -0.12065 -0.3048)
			(end -0.67945 -0.3048)
			(stroke
				(width 0.1)
				(type default)
			)
			(layer "B.Fab")
		)
		(fp_line
			(start -0.67945 -0.3048)
			(end -0.67945 0.3048)
			(stroke
				(width 0.1)
				(type default)
			)
			(layer "B.Fab")
		)
		(fp_line
			(start 0.12065 -0.2794)
			(end -0.12065 -0.2794)
			(stroke
				(width 0.1)
				(type default)
			)
			(layer "B.Fab")
		)
		(fp_line
			(start -0.12065 -0.2794)
			(end -0.12065 -0.3048)
			(stroke
				(width 0.1)
				(type default)
			)
			(layer "B.Fab")
		)
		(fp_line
			(start 0.12065 0.2794)
			(end 0.12065 0.3048)
			(stroke
				(width 0.1)
				(type default)
			)
			(layer "B.Fab")
		)
		(fp_line
			(start -0.120396 0.2794)
			(end 0.12065 0.2794)
			(stroke
				(width 0.1)
				(type default)
			)
			(layer "B.Fab")
		)
		(fp_line
			(start 0.67945 0.3048)
			(end 0.67945 -0.305054)
			(stroke
				(width 0.1)
				(type default)
			)
			(layer "B.Fab")
		)
		(fp_line
			(start 0.12065 0.3048)
			(end 0.67945 0.3048)
			(stroke
				(width 0.1)
				(type default)
			)
			(layer "B.Fab")
		)
		(fp_line
			(start -0.120396 0.3048)
			(end -0.120396 0.2794)
			(stroke
				(width 0.1)
				(type default)
			)
			(layer "B.Fab")
		)
		(fp_line
			(start -0.67945 0.3048)
			(end -0.120396 0.3048)
			(stroke
				(width 0.1)
				(type default)
			)
			(layer "B.Fab")
		)
		(pad "1" smd circle
			(at 0.40005 0 270)
			(size 0 0)
			(layers "B.Cu" "B.Mask" "B.Paste")
			(net "P1V8_PEX")
		)
		(pad "2" smd circle
			(at -0.40005 0 270)
			(size 0 0)
			(layers "B.Cu" "B.Mask" "B.Paste")
			(net "SMB_PEX0_MUX_SDA")
		)
	)
)
